(kicad_pcb
	(version 20260206)
	(generator "pcbnew")
	(generator_version "10.0")
	(general
		(thickness 1.6)
		(legacy_teardrops no)
	)
	(paper "A4")
	(title_block
		(title "Bryce Canyon_F.DPB_16315-1-OCP.brd")
		(comment 1 "Bryce Canyon / footprints 527-529 of 2223")
	)
	(layers
		(0 "F.Cu" signal "TOP")
		(4 "In1.Cu" signal "L2GND")
		(6 "In2.Cu" signal "L3")
		(8 "In3.Cu" signal "L4GND")
		(10 "In4.Cu" signal "L5")
		(12 "In5.Cu" signal "L6VCC")
		(14 "In6.Cu" signal "L7VCC")
		(16 "In7.Cu" signal "L8")
		(18 "In8.Cu" signal "L9GND")
		(20 "In9.Cu" signal "L10")
		(22 "In10.Cu" signal "L11GND")
		(2 "B.Cu" signal "BOTTOM")
		(9 "F.Adhes" user "F.Adhesive")
		(11 "B.Adhes" user "B.Adhesive")
		(13 "F.Paste" user "Package Geometry/Pastemask Top")
		(15 "B.Paste" user "Package Geometry/Pastemask Bottom")
		(5 "F.SilkS" user "Ref Des/Silkscreen Top")
		(7 "B.SilkS" user "Ref Des/Silkscreen Bottom")
		(1 "F.Mask" user "Board Geometry/Soldermask Top")
		(3 "B.Mask" user "Board Geometry/Soldermask Bottom")
		(17 "Dwgs.User" user "User.Drawings")
		(19 "Cmts.User" user "User.Comments")
		(21 "Eco1.User" user "User.Eco1")
		(23 "Eco2.User" user "User.Eco2")
		(25 "Edge.Cuts" user "Board Geometry/Outline")
		(27 "Margin" user)
		(31 "F.CrtYd" user "Package Geometry/Place Bound Top")
		(29 "B.CrtYd" user "Package Geometry/Place Bound Bottom")
		(35 "F.Fab" user "Ref Des/Assembly Top")
		(33 "B.Fab" user "Ref Des/Assembly Bottom")
	)
	(footprint ""
		(layer "F.Cu")
		(at 67.728846 -295.064942 90)
		(property "Reference" "R155"
			(at 0 0 90)
			(layer "F.SilkS")
			(hide yes)
			(effects
				(font
					(size 1.27 1.27)
				)
			)
		)
		(property "Value" "220R3F-1-GP"
			(at -0.0254 -2.5146 90)
			(unlocked yes)
			(layer "F.Fab")
			(hide yes)
			(effects
				(font
					(size 1.016 1.016)
					(thickness 0.1524)
				)
			)
		)
		(property "Device Type" "R603H22"
			(at -0.0254 -4.0386 90)
			(unlocked yes)
			(layer "F.Fab")
			(hide yes)
			(effects
				(font
					(size 1.016 1.016)
					(thickness 0.1524)
				)
			)
		)
		(duplicate_pad_numbers_are_jumpers no)
		(fp_line
			(start 0.2032 0)
			(end 0.4826 0)
			(stroke
				(width 0.2032)
				(type default)
			)
			(layer "F.SilkS")
		)
		(fp_line
			(start -0.4826 0)
			(end -0.2032 0)
			(stroke
				(width 0.2032)
				(type default)
			)
			(layer "F.SilkS")
		)
		(fp_rect
			(start -0.5842 1.3335)
			(end 0.5842 -1.3335)
			(stroke
				(width 0)
				(type default)
			)
			(fill no)
			(layer "F.CrtYd")
		)
		(fp_rect
			(start -0.5842 1.3335)
			(end 0.5842 -1.3335)
			(stroke
				(width 0)
				(type default)
			)
			(fill no)
			(layer "F.Fab")
		)
		(pad "1" smd custom
			(at 0 -0.762 90)
			(size 0.2159 0.2159)
			(layers "F.Cu" "F.Mask" "F.Paste")
			(net "HDD_PRSNT_1")
			(options
				(clearance outline)
				(anchor circle)
			)
			(primitives
				(gr_poly
					(pts
						(arc
							(start -0.3302 -0.4318)
							(mid -0.402042 -0.402042)
							(end -0.4318 -0.3302)
						)
						(arc
							(start -0.4318 0.3302)
							(mid -0.402042 0.402042)
							(end -0.3302 0.4318)
						)
						(arc
							(start 0.3302 0.4318)
							(mid 0.402042 0.402042)
							(end 0.4318 0.3302)
						)
						(arc
							(start 0.4318 -0.3302)
							(mid 0.402042 -0.402042)
							(end 0.3302 -0.4318)
						)
					)
					(width 0)
					(fill yes)
				)
			)
		)
		(pad "2" smd custom
			(at 0 0.762 90)
			(size 0.2159 0.2159)
			(layers "F.Cu" "F.Mask" "F.Paste")
			(net "DRIVE_A_1_INS")
			(options
				(clearance outline)
				(anchor circle)
			)
			(primitives
				(gr_poly
					(pts
						(arc
							(start -0.3302 -0.4318)
							(mid -0.402042 -0.402042)
							(end -0.4318 -0.3302)
						)
						(arc
							(start -0.4318 0.3302)
							(mid -0.402042 0.402042)
							(end -0.3302 0.4318)
						)
						(arc
							(start 0.3302 0.4318)
							(mid 0.402042 0.402042)
							(end 0.4318 0.3302)
						)
						(arc
							(start 0.4318 -0.3302)
							(mid 0.402042 -0.402042)
							(end 0.3302 -0.4318)
						)
					)
					(width 0)
					(fill yes)
				)
			)
		)
	)
	(footprint ""
		(layer "F.Cu")
		(at 28.200096 -172.909992 -90)
		(property "Reference" "HDDSAS12"
			(at 0 0 270)
			(layer "F.SilkS")
			(hide yes)
			(effects
				(font
					(size 1.27 1.27)
				)
			)
		)
		(property "Value" "SKT-SAS15P-14P-45-GP"
			(at -20.7645 -8.9789 270)
			(unlocked yes)
			(layer "F.Fab")
			(hide yes)
			(effects
				(font
					(size 1.016 1.016)
					(thickness 0.1524)
				)
			)
		)
		(property "Device Type" "10120818-001C-TRLF"
			(at -20.7645 -10.5029 270)
			(unlocked yes)
			(layer "F.Fab")
			(hide yes)
			(effects
				(font
					(size 1.016 1.016)
					(thickness 0.1524)
				)
			)
		)
		(duplicate_pad_numbers_are_jumpers no)
		(fp_line
			(start 1.651 4.2926)
			(end 1.651 3.0099)
			(stroke
				(width 0.1524)
				(type default)
			)
			(layer "F.SilkS")
		)
		(fp_line
			(start 8.509 4.2926)
			(end 1.651 4.2926)
			(stroke
				(width 0.1524)
				(type default)
			)
			(layer "F.SilkS")
		)
		(fp_line
			(start -23.4188 3.0099)
			(end -23.4188 -3.2512)
			(stroke
				(width 0.1524)
				(type default)
			)
			(layer "F.SilkS")
		)
		(fp_line
			(start 1.651 3.0099)
			(end -23.4188 3.0099)
			(stroke
				(width 0.1524)
				(type default)
			)
			(layer "F.SilkS")
		)
		(fp_line
			(start 8.509 3.0099)
			(end 8.509 4.2926)
			(stroke
				(width 0.1524)
				(type default)
			)
			(layer "F.SilkS")
		)
		(fp_line
			(start 23.4188 3.0099)
			(end 8.509 3.0099)
			(stroke
				(width 0.1524)
				(type default)
			)
			(layer "F.SilkS")
		)
		(fp_line
			(start -23.4188 -3.2512)
			(end 23.4188 -3.2512)
			(stroke
				(width 0.1524)
				(type default)
			)
			(layer "F.SilkS")
		)
		(fp_line
			(start 23.4188 -3.2512)
			(end 23.4188 3.0099)
			(stroke
				(width 0.1524)
				(type default)
			)
			(layer "F.SilkS")
		)
		(fp_line
			(start 15.5067 -3.3401)
			(end 16.2687 -3.3401)
			(stroke
				(width 0.3302)
				(type default)
			)
			(layer "F.SilkS")
		)
		(fp_poly
			(pts
				(xy 15.868904 -3.230372) (xy 16.503904 -3.865372) (xy 15.233904 -3.865372)
			)
			(stroke
				(width 0)
				(type default)
			)
			(fill yes)
			(layer "F.SilkS")
		)
		(fp_poly
			(pts
				(xy -22.8727 -2.7559) (xy 22.8727 -2.7559) (xy 22.8727 2.7559) (xy 8.255 2.7559) (xy 8.255 3.5179)
				(xy 1.905 3.5179) (xy 1.905 2.7559) (xy -22.8727 2.7559)
			)
			(stroke
				(width 0)
				(type default)
			)
			(fill no)
			(layer "F.CrtYd")
		)
		(fp_poly
			(pts
				(xy 1.397 4.5466) (xy 1.397 3.2639) (xy -23.6728 3.2639) (xy -23.6728 -3.5052) (xy 23.6728 -3.5052)
				(xy 23.6728 -0.00635) (xy 22.8727 -0.00635) (xy 22.8727 -2.7559) (xy -22.8727 -2.7559) (xy -22.8727 2.7559)
				(xy 1.905 2.7559) (xy 1.905 3.5179) (xy 8.255 3.5179) (xy 8.255 2.7559) (xy 22.8727 2.7559) (xy 22.8727 0.00635)
				(xy 23.6728 0.00635) (xy 23.6728 3.2639) (xy 8.763 3.2639) (xy 8.763 4.5466)
			)
			(stroke
				(width 0)
				(type default)
			)
			(fill no)
			(layer "F.CrtYd")
		)
		(fp_poly
			(pts
				(xy 1.397 4.5466) (xy 1.397 3.2639) (xy -23.6728 3.2639) (xy -23.6728 -3.5052) (xy 23.6728 -3.5052)
				(xy 23.6728 3.2639) (xy 8.763 3.2639) (xy 8.763 4.5466)
			)
			(stroke
				(width 0)
				(type default)
			)
			(fill no)
			(layer "F.Fab")
		)
		(pad "" np_thru_hole circle
			(at -18.874994 0 270)
			(size 0.254 0.254)
			(drill 1.3462)
			(layers "*.Cu" "*.Mask")
			(clearance 0.9017)
			(thermal_gap 0.9017)
		)
		(pad "" np_thru_hole circle
			(at 18.874994 0 270)
			(size 0.254 0.254)
			(drill 0.9398)
			(layers "*.Cu" "*.Mask")
			(clearance 0.6985)
			(thermal_gap 0.6985)
		)
		(pad "G1" smd rect
			(at 21.874988 0 270)
			(size 2.5908 2.5908)
			(layers "F.Cu" "F.Mask" "F.Paste")
			(net "GND")
		)
		(pad "G2" smd rect
			(at -21.874988 0 270)
			(size 2.5908 2.5908)
			(layers "F.Cu" "F.Mask" "F.Paste")
			(net "GND")
		)
		(pad "P1" smd rect
			(at 1.905 -1.82499 270)
			(size 0.6096 2.3622)
			(layers "F.Cu" "F.Mask" "F.Paste")
			(net "Net_2156")
		)
		(pad "P2" smd rect
			(at 0.635 -1.82499 270)
			(size 0.6096 2.3622)
			(layers "F.Cu" "F.Mask" "F.Paste")
			(net "Net_2157")
		)
		(pad "P3" smd rect
			(at -0.635 -1.82499 270)
			(size 0.6096 2.3622)
			(layers "F.Cu" "F.Mask" "F.Paste")
			(net "Net_2158")
		)
		(pad "P4" smd rect
			(at -1.905 -1.82499 270)
			(size 0.6096 2.3622)
			(layers "F.Cu" "F.Mask" "F.Paste")
			(net "GND")
		)
		(pad "P5" smd rect
			(at -3.175 -1.82499 270)
			(size 0.6096 2.3622)
			(layers "F.Cu" "F.Mask" "F.Paste")
			(net "HDD_PRSNT_12")
		)
		(pad "P6" smd rect
			(at -4.445 -1.82499 270)
			(size 0.6096 2.3622)
			(layers "F.Cu" "F.Mask" "F.Paste")
			(net "GND")
		)
		(pad "P7" smd rect
			(at -5.715 -1.82499 270)
			(size 0.6096 2.3622)
			(layers "F.Cu" "F.Mask" "F.Paste")
			(net "5V_PRE_12")
		)
		(pad "P8" smd rect
			(at -6.985 -1.82499 270)
			(size 0.6096 2.3622)
			(layers "F.Cu" "F.Mask" "F.Paste")
			(net "P5V_HDD12")
		)
		(pad "P9" smd rect
			(at -8.255 -1.82499 270)
			(size 0.6096 2.3622)
			(layers "F.Cu" "F.Mask" "F.Paste")
			(net "P5V_HDD12")
		)
		(pad "P10" smd rect
			(at -9.525 -1.82499 270)
			(size 0.6096 2.3622)
			(layers "F.Cu" "F.Mask" "F.Paste")
			(net "GND")
		)
		(pad "P11" smd rect
			(at -10.795 -1.82499 270)
			(size 0.6096 2.3622)
			(layers "F.Cu" "F.Mask" "F.Paste")
			(net "ACT_HDD_12")
		)
		(pad "P12" smd rect
			(at -12.065 -1.82499 270)
			(size 0.6096 2.3622)
			(layers "F.Cu" "F.Mask" "F.Paste")
			(net "GND")
		)
		(pad "P13" smd rect
			(at -13.335 -1.82499 270)
			(size 0.6096 2.3622)
			(layers "F.Cu" "F.Mask" "F.Paste")
			(net "12V_PRE_12")
		)
		(pad "P14" smd rect
			(at -14.605 -1.82499 270)
			(size 0.6096 2.3622)
			(layers "F.Cu" "F.Mask" "F.Paste")
			(net "P12V_HDD12")
		)
		(pad "P15" smd rect
			(at -15.875 -1.82499 270)
			(size 0.6096 2.3622)
			(layers "F.Cu" "F.Mask" "F.Paste")
			(net "P12V_HDD12")
		)
		(pad "S1" smd rect
			(at 15.875 -1.82499 270)
			(size 0.6096 2.3622)
			(layers "F.Cu" "F.Mask" "F.Paste")
			(net "GND")
		)
		(pad "S2" smd rect
			(at 14.605 -1.82499 270)
			(size 0.6096 2.3622)
			(layers "F.Cu" "F.Mask" "F.Paste")
			(net "SAS_HDD_RX_P12")
		)
		(pad "S3" smd rect
			(at 13.335 -1.82499 270)
			(size 0.6096 2.3622)
			(layers "F.Cu" "F.Mask" "F.Paste")
			(net "SAS_HDD_RX_N12")
		)
		(pad "S4" smd rect
			(at 12.065 -1.82499 270)
			(size 0.6096 2.3622)
			(layers "F.Cu" "F.Mask" "F.Paste")
			(net "GND")
		)
		(pad "S5" smd rect
			(at 10.795 -1.82499 270)
			(size 0.6096 2.3622)
			(layers "F.Cu" "F.Mask" "F.Paste")
			(net "PHY_DRV_A_TO_SCC_A_12_DN")
		)
		(pad "S6" smd rect
			(at 9.525 -1.82499 270)
			(size 0.6096 2.3622)
			(layers "F.Cu" "F.Mask" "F.Paste")
			(net "PHY_DRV_A_TO_SCC_A_12_DP")
		)
		(pad "S7" smd rect
			(at 8.255 -1.82499 270)
			(size 0.6096 2.3622)
			(layers "F.Cu" "F.Mask" "F.Paste")
			(net "GND")
		)
		(pad "S8" smd rect
			(at 7.480046 2.845054 270)
			(size 0.508 2.3622)
			(layers "F.Cu" "F.Mask" "F.Paste")
			(net "GND")
		)
		(pad "S9" smd rect
			(at 6.679946 2.845054 270)
			(size 0.508 2.3622)
			(layers "F.Cu" "F.Mask" "F.Paste")
			(net "Net_449")
		)
		(pad "S10" smd rect
			(at 5.8801 2.845054 270)
			(size 0.508 2.3622)
			(layers "F.Cu" "F.Mask" "F.Paste")
			(net "Net_341")
		)
		(pad "S11" smd rect
			(at 5.08 2.845054 270)
			(size 0.508 2.3622)
			(layers "F.Cu" "F.Mask" "F.Paste")
			(net "GND")
		)
		(pad "S12" smd rect
			(at 4.2799 2.845054 270)
			(size 0.508 2.3622)
			(layers "F.Cu" "F.Mask" "F.Paste")
			(net "Net_377")
		)
		(pad "S13" smd rect
			(at 3.480054 2.845054 270)
			(size 0.508 2.3622)
			(layers "F.Cu" "F.Mask" "F.Paste")
			(net "Net_413")
		)
		(pad "S14" smd rect
			(at 2.679954 2.845054 270)
			(size 0.508 2.3622)
			(layers "F.Cu" "F.Mask" "F.Paste")
			(net "GND")
		)
		(zone
			(layer "F.Cu")
			(hatch none 0.5)
			(connect_pads
				(clearance 0)
			)
			(min_thickness 0.25)
			(keepout
				(tracks allowed)
				(vias not_allowed)
				(pads allowed)
				(copperpour not_allowed)
				(footprints allowed)
			)
			(placement
				(enabled no)
				(sheetname "")
			)
			(fill
				(thermal_gap 0.5)
				(thermal_bridge_width 0.5)
				(island_removal_mode 0)
			)
			(polygon
				(pts
					(xy 31.857696 -189.648592) (xy 24.783796 -189.648592) (xy 24.783796 -196.582792) (xy 25.888696 -196.582792)
					(xy 25.888696 -192.467992) (xy 30.511496 -192.467992) (xy 30.511496 -196.582792) (xy 31.857696 -196.582792)
				)
			)
		)
		(zone
			(layer "F.Cu")
			(hatch none 0.5)
			(connect_pads
				(clearance 0)
			)
			(min_thickness 0.25)
			(keepout
				(tracks not_allowed)
				(vias allowed)
				(pads allowed)
				(copperpour not_allowed)
				(footprints allowed)
			)
			(placement
				(enabled no)
				(sheetname "")
			)
			(fill
				(thermal_gap 0.5)
				(thermal_bridge_width 0.5)
				(island_removal_mode 0)
			)
			(polygon
				(pts
					(xy 31.857696 -189.648592) (xy 24.783796 -189.648592) (xy 24.783796 -196.582792) (xy 25.888696 -196.582792)
					(xy 25.888696 -192.467992) (xy 30.511496 -192.467992) (xy 30.511496 -196.582792) (xy 31.857696 -196.582792)
				)
			)
		)
		(zone
			(layer "F.Cu")
			(hatch none 0.5)
			(connect_pads
				(clearance 0)
			)
			(min_thickness 0.25)
			(keepout
				(tracks allowed)
				(vias not_allowed)
				(pads allowed)
				(copperpour not_allowed)
				(footprints allowed)
			)
			(placement
				(enabled no)
				(sheetname "")
			)
			(fill
				(thermal_gap 0.5)
				(thermal_bridge_width 0.5)
				(island_removal_mode 0)
			)
			(polygon
				(pts
					(xy 31.857696 -156.171392) (xy 24.783796 -156.171392) (xy 24.783796 -149.237192) (xy 25.888696 -149.237192)
					(xy 25.888696 -153.351992) (xy 30.511496 -153.351992) (xy 30.511496 -149.237192) (xy 31.857696 -149.237192)
				)
			)
		)
		(zone
			(layer "F.Cu")
			(hatch none 0.5)
			(connect_pads
				(clearance 0)
			)
			(min_thickness 0.25)
			(keepout
				(tracks not_allowed)
				(vias allowed)
				(pads allowed)
				(copperpour not_allowed)
				(footprints allowed)
			)
			(placement
				(enabled no)
				(sheetname "")
			)
			(fill
				(thermal_gap 0.5)
				(thermal_bridge_width 0.5)
				(island_removal_mode 0)
			)
			(polygon
				(pts
					(xy 31.857696 -156.171392) (xy 24.783796 -156.171392) (xy 24.783796 -149.237192) (xy 25.888696 -149.237192)
					(xy 25.888696 -153.351992) (xy 30.511496 -153.351992) (xy 30.511496 -149.237192) (xy 31.857696 -149.237192)
				)
			)
		)
		(zone
			(layers "F.Cu" "B.Cu" "In1.Cu" "In2.Cu" "In3.Cu" "In4.Cu" "In5.Cu" "In6.Cu"
				"In7.Cu" "In8.Cu" "In9.Cu" "In10.Cu"
			)
			(hatch none 0.5)
			(connect_pads
				(clearance 0)
			)
			(min_thickness 0.25)
			(keepout
				(tracks not_allowed)
				(vias allowed)
				(pads allowed)
				(copperpour not_allowed)
				(footprints allowed)
			)
			(placement
				(enabled no)
				(sheetname "")
			)
			(fill
				(thermal_gap 0.5)
				(thermal_bridge_width 0.5)
				(island_removal_mode 0)
			)
			(polygon
				(pts
					(arc
						(start 28.974796 -154.034998)
						(mid 27.425396 -154.034998)
						(end 28.974796 -154.034998)
					)
				)
			)
		)
		(zone
			(layers "F.Cu" "B.Cu" "In1.Cu" "In2.Cu" "In3.Cu" "In4.Cu" "In5.Cu" "In6.Cu"
				"In7.Cu" "In8.Cu" "In9.Cu" "In10.Cu"
			)
			(hatch none 0.5)
			(connect_pads
				(clearance 0)
			)
			(min_thickness 0.25)
			(keepout
				(tracks not_allowed)
				(vias allowed)
				(pads allowed)
				(copperpour not_allowed)
				(footprints allowed)
			)
			(placement
				(enabled no)
				(sheetname "")
			)
			(fill
				(thermal_gap 0.5)
				(thermal_bridge_width 0.5)
				(island_removal_mode 0)
			)
			(polygon
				(pts
					(arc
						(start 29.177996 -191.784986)
						(mid 27.222196 -191.784986)
						(end 29.177996 -191.784986)
					)
				)
			)
		)
	)
	(footprint ""
		(layer "F.Cu")
		(at 406.9588 -282.6766)
		(property "Reference" "R329"
			(at 0 0 0)
			(layer "F.SilkS")
			(hide yes)
			(effects
				(font
					(size 1.27 1.27)
				)
			)
		)
		(property "Value" "300KR2F-GP"
			(at 0.064008 -3.993896 0)
			(unlocked yes)
			(layer "F.Fab")
			(hide yes)
			(effects
				(font
					(size 1.016 1.016)
					(thickness 0.1524)
				)
			)
		)
		(property "Device Type" "R402H16"
			(at 0.064008 -5.517896 0)
			(unlocked yes)
			(layer "F.Fab")
			(hide yes)
			(effects
				(font
					(size 1.016 1.016)
					(thickness 0.1524)
				)
			)
		)
		(duplicate_pad_numbers_are_jumpers no)
		(fp_line
			(start -0.508 -0.9398)
			(end -0.508 0.9398)
			(stroke
				(width 0.1524)
				(type default)
			)
			(layer "F.SilkS")
		)
		(fp_line
			(start 0.508 -0.9398)
			(end -0.508 -0.9398)
			(stroke
				(width 0.1524)
				(type default)
			)
			(layer "F.SilkS")
		)
		(fp_rect
			(start -0.508 0.9398)
			(end 0.508 -0.9398)
			(stroke
				(width 0)
				(type default)
			)
			(fill no)
			(layer "F.CrtYd")
		)
		(fp_rect
			(start -0.508 0.9398)
			(end 0.508 -0.9398)
			(stroke
				(width 0)
				(type default)
			)
			(fill no)
			(layer "F.Fab")
		)
		(pad "1" smd custom
			(at 0 -0.4445)
			(size 0.1397 0.1397)
			(layers "F.Cu" "F.Mask" "F.Paste")
			(net "SW_HDD_N8")
			(options
				(clearance outline)
				(anchor circle)
			)
			(primitives
				(gr_poly
					(pts
						(arc
							(start -0.1778 -0.2794)
							(mid -0.249642 -0.249642)
							(end -0.2794 -0.1778)
						)
						(arc
							(start -0.2794 0.1778)
							(mid -0.249642 0.249642)
							(end -0.1778 0.2794)
						)
						(arc
							(start 0.1778 0.2794)
							(mid 0.249642 0.249642)
							(end 0.2794 0.1778)
						)
						(arc
							(start 0.2794 -0.1778)
							(mid 0.249642 -0.249642)
							(end 0.1778 -0.2794)
						)
					)
					(width 0)
					(fill yes)
				)
			)
		)
		(pad "2" smd custom
			(at 0 0.4445)
			(size 0.1397 0.1397)
			(layers "F.Cu" "F.Mask" "F.Paste")
			(net "P12V_A")
			(options
				(clearance outline)
				(anchor circle)
			)
			(primitives
				(gr_poly
					(pts
						(arc
							(start -0.1778 -0.2794)
							(mid -0.249642 -0.249642)
							(end -0.2794 -0.1778)
						)
						(arc
							(start -0.2794 0.1778)
							(mid -0.249642 0.249642)
							(end -0.1778 0.2794)
						)
						(arc
							(start 0.1778 0.2794)
							(mid 0.249642 0.249642)
							(end 0.2794 0.1778)
						)
						(arc
							(start 0.2794 -0.1778)
							(mid 0.249642 -0.249642)
							(end 0.1778 -0.2794)
						)
					)
					(width 0)
					(fill yes)
				)
			)
		)
	)
)
